(kicad_pcb
	(version 20260206)
	(generator "pcbnew")
	(generator_version "10.0")
	(general
		(thickness 1.6)
		(legacy_teardrops no)
	)
	(paper "A4")
	(title_block
		(title "v1-chassis-manager — T6M_CM_d_v01_1031_1645.brd")
		(comment 1 "Open CloudServer (Microsoft) / footprints 1165-1170 of 2512")
	)
	(layers
		(0 "F.Cu" signal "TOP")
		(4 "In1.Cu" signal "GND1")
		(6 "In2.Cu" signal "IN1")
		(8 "In3.Cu" signal "VCC1")
		(10 "In4.Cu" signal "VCC2")
		(12 "In5.Cu" signal "GND2")
		(14 "In6.Cu" signal "IN2")
		(16 "In7.Cu" signal "IN3")
		(18 "In8.Cu" signal "GND3")
		(2 "B.Cu" signal "BOTTOM")
		(9 "F.Adhes" user "F.Adhesive")
		(11 "B.Adhes" user "B.Adhesive")
		(13 "F.Paste" user "Package Geometry/Pastemask Top")
		(15 "B.Paste" user "Package Geometry/Pastemask Bottom")
		(5 "F.SilkS" user "Ref Des/Silkscreen Top")
		(7 "B.SilkS" user "Ref Des/Silkscreen Bottom")
		(1 "F.Mask" user "Board Geometry/Soldermask Top")
		(3 "B.Mask" user "Board Geometry/Soldermask Bottom")
		(17 "Dwgs.User" user "User.Drawings")
		(19 "Cmts.User" user "User.Comments")
		(21 "Eco1.User" user "User.Eco1")
		(23 "Eco2.User" user "User.Eco2")
		(25 "Edge.Cuts" user "Board Geometry/Outline")
		(27 "Margin" user)
		(31 "F.CrtYd" user "Package Geometry/Place Bound Top")
		(29 "B.CrtYd" user "Package Geometry/Place Bound Bottom")
		(35 "F.Fab" user "Ref Des/Assembly Top")
		(33 "B.Fab" user "Ref Des/Assembly Bottom")
	)
	(footprint ""
		(layer "F.Cu")
		(at 150.055326 -41.881044 -90)
		(property "Reference" "R1011"
			(at -0.355346 -10.260076 90)
			(unlocked yes)
			(layer "F.SilkS")
			(effects
				(font
					(size 0.7874 0.5842)
					(thickness 0.1524)
				)
				(justify left)
			)
		)
		(property "Value" ""
			(at 0 0 270)
			(layer "F.Fab")
			(effects
				(font
					(size 1.27 1.27)
				)
			)
		)
		(duplicate_pad_numbers_are_jumpers no)
		(fp_line
			(start -0.7874 0.4064)
			(end -0.7874 -0.4064)
			(stroke
				(width 0.1524)
				(type default)
			)
			(layer "F.SilkS")
		)
		(fp_line
			(start 0.7874 0.4064)
			(end -0.7874 0.4064)
			(stroke
				(width 0.1524)
				(type default)
			)
			(layer "F.SilkS")
		)
		(fp_line
			(start -0.7874 -0.4064)
			(end 0.7874 -0.4064)
			(stroke
				(width 0.1524)
				(type default)
			)
			(layer "F.SilkS")
		)
		(fp_line
			(start 0.7874 -0.4064)
			(end 0.7874 0.4064)
			(stroke
				(width 0.1524)
				(type default)
			)
			(layer "F.SilkS")
		)
		(fp_poly
			(pts
				(xy -0.508 0.2794) (xy -0.508 0.2286) (xy -0.635 0.2286) (xy -0.635 -0.254) (xy -0.5334 -0.254)
				(xy -0.5334 -0.2794) (xy 0.5334 -0.2794) (xy 0.5334 -0.254) (xy 0.635 -0.254) (xy 0.635 0.254) (xy 0.5334 0.254)
				(xy 0.5334 0.2794)
			)
			(stroke
				(width 0)
				(type default)
			)
			(fill no)
			(layer "F.CrtYd")
		)
		(pad "1" smd rect
			(at 0.40005 0 270)
			(size 0.4572 0.508)
			(layers "F.Cu" "F.Mask" "F.Paste")
			(net "P5V_NODE1")
		)
		(pad "2" smd rect
			(at -0.40005 0 270)
			(size 0.4572 0.508)
			(layers "F.Cu" "F.Mask" "F.Paste")
			(net "UART_RTS_P1_N")
		)
	)
	(footprint ""
		(layer "F.Cu")
		(at 154.983688 -178.689254 -90)
		(property "Reference" "R1168"
			(at -1.157732 1.076198 90)
			(unlocked yes)
			(layer "F.SilkS")
			(effects
				(font
					(size 0.7874 0.5842)
					(thickness 0.1524)
				)
				(justify left)
			)
		)
		(property "Value" ""
			(at 0 0 270)
			(layer "F.Fab")
			(effects
				(font
					(size 1.27 1.27)
				)
			)
		)
		(duplicate_pad_numbers_are_jumpers no)
		(fp_line
			(start -0.7874 0.4064)
			(end -0.7874 -0.4064)
			(stroke
				(width 0.1524)
				(type default)
			)
			(layer "F.SilkS")
		)
		(fp_line
			(start 0.7874 0.4064)
			(end -0.7874 0.4064)
			(stroke
				(width 0.1524)
				(type default)
			)
			(layer "F.SilkS")
		)
		(fp_line
			(start -0.7874 -0.4064)
			(end 0.7874 -0.4064)
			(stroke
				(width 0.1524)
				(type default)
			)
			(layer "F.SilkS")
		)
		(fp_line
			(start 0.7874 -0.4064)
			(end 0.7874 0.4064)
			(stroke
				(width 0.1524)
				(type default)
			)
			(layer "F.SilkS")
		)
		(fp_poly
			(pts
				(xy -0.508 0.2794) (xy -0.508 0.2286) (xy -0.635 0.2286) (xy -0.635 -0.254) (xy -0.5334 -0.254)
				(xy -0.5334 -0.2794) (xy 0.5334 -0.2794) (xy 0.5334 -0.254) (xy 0.635 -0.254) (xy 0.635 0.254) (xy 0.5334 0.254)
				(xy 0.5334 0.2794)
			)
			(stroke
				(width 0)
				(type default)
			)
			(fill no)
			(layer "F.CrtYd")
		)
		(pad "1" smd rect
			(at 0.40005 0 270)
			(size 0.4572 0.508)
			(layers "F.Cu" "F.Mask" "F.Paste")
			(net "CPLD_UART_RX_P3")
		)
		(pad "2" smd rect
			(at -0.40005 0 270)
			(size 0.4572 0.508)
			(layers "F.Cu" "F.Mask" "F.Paste")
			(net "GND")
		)
	)
	(footprint ""
		(layer "F.Cu")
		(at 45.858684 -109.977936)
		(property "Reference" "PU2"
			(at 2.526538 2.727452 90)
			(unlocked yes)
			(layer "F.SilkS")
			(effects
				(font
					(size 0.7874 0.5842)
					(thickness 0.1524)
				)
				(justify left)
			)
		)
		(property "Value" ""
			(at 0 0 0)
			(layer "F.Fab")
			(effects
				(font
					(size 1.27 1.27)
				)
			)
		)
		(duplicate_pad_numbers_are_jumpers no)
		(fp_line
			(start -1.575054 -1.575054)
			(end -1.575054 -1.0414)
			(stroke
				(width 0.1524)
				(type default)
			)
			(layer "F.SilkS")
		)
		(fp_line
			(start -1.575054 1.0922)
			(end -1.575054 1.575054)
			(stroke
				(width 0.1524)
				(type default)
			)
			(layer "F.SilkS")
		)
		(fp_line
			(start -1.575054 1.575054)
			(end -1.0922 1.575054)
			(stroke
				(width 0.1524)
				(type default)
			)
			(layer "F.SilkS")
		)
		(fp_line
			(start -1.0668 -1.575054)
			(end -1.575054 -1.575054)
			(stroke
				(width 0.1524)
				(type default)
			)
			(layer "F.SilkS")
		)
		(fp_line
			(start -0.750062 2.043938)
			(end -0.750062 2.348738)
			(stroke
				(width 0.1524)
				(type default)
			)
			(layer "F.SilkS")
		)
		(fp_line
			(start -0.255778 -2.350262)
			(end -0.255778 -2.045462)
			(stroke
				(width 0.1524)
				(type default)
			)
			(layer "F.SilkS")
		)
		(fp_line
			(start 1.0414 1.575054)
			(end 1.575054 1.575054)
			(stroke
				(width 0.1524)
				(type default)
			)
			(layer "F.SilkS")
		)
		(fp_line
			(start 1.575054 -1.575054)
			(end 1.0414 -1.575054)
			(stroke
				(width 0.1524)
				(type default)
			)
			(layer "F.SilkS")
		)
		(fp_line
			(start 1.575054 -1.0668)
			(end 1.575054 -1.575054)
			(stroke
				(width 0.1524)
				(type default)
			)
			(layer "F.SilkS")
		)
		(fp_line
			(start 1.575054 1.575054)
			(end 1.575054 1.143)
			(stroke
				(width 0.1524)
				(type default)
			)
			(layer "F.SilkS")
		)
		(fp_line
			(start 2.055622 0.25019)
			(end 2.563622 0.25019)
			(stroke
				(width 0.1524)
				(type default)
			)
			(layer "F.SilkS")
		)
		(fp_poly
			(pts
				(xy -1.69291 -1.110742) (xy -2.230374 -2.18567) (xy -2.767584 -1.648206)
			)
			(stroke
				(width 0)
				(type default)
			)
			(fill yes)
			(layer "F.SilkS")
		)
		(fp_poly
			(pts
				(xy -1.575054 1.575054) (xy -0.9398 1.575054) (xy -0.9398 1.9558) (xy 0.9398 1.9558) (xy 0.9398 1.575054)
				(xy 1.575054 1.575054) (xy 1.575054 0.9398) (xy 1.9558 0.9398) (xy 1.9558 -0.9398) (xy 1.575054 -0.9398)
				(xy 1.575054 -1.575054) (xy 0.9398 -1.575054) (xy 0.9398 -1.9558) (xy -0.9398 -1.9558) (xy -0.9398 -1.575054)
				(xy -1.575054 -1.575054) (xy -1.575054 -0.9398) (xy -1.9558 -0.9398) (xy -1.9558 0.9398) (xy -1.575054 0.9398)
			)
			(stroke
				(width 0)
				(type default)
			)
			(fill no)
			(layer "F.CrtYd")
		)
		(fp_line
			(start -1.575054 -1.575054)
			(end 1.575054 -1.575054)
			(stroke
				(width 0.1)
				(type default)
			)
			(layer "F.Fab")
		)
		(fp_line
			(start -1.575054 1.575054)
			(end -1.575054 -1.575054)
			(stroke
				(width 0.1)
				(type default)
			)
			(layer "F.Fab")
		)
		(fp_line
			(start -0.750062 2.043938)
			(end -0.750062 2.348738)
			(stroke
				(width 0.1)
				(type default)
			)
			(layer "F.Fab")
		)
		(fp_line
			(start -0.255778 -2.350262)
			(end -0.255778 -2.045462)
			(stroke
				(width 0.1)
				(type default)
			)
			(layer "F.Fab")
		)
		(fp_line
			(start 1.575054 -1.575054)
			(end 1.575054 1.575054)
			(stroke
				(width 0.1)
				(type default)
			)
			(layer "F.Fab")
		)
		(fp_line
			(start 1.575054 1.575054)
			(end -1.575054 1.575054)
			(stroke
				(width 0.1)
				(type default)
			)
			(layer "F.Fab")
		)
		(fp_line
			(start 2.055622 0.25019)
			(end 2.563622 0.25019)
			(stroke
				(width 0.1)
				(type default)
			)
			(layer "F.Fab")
		)
		(fp_poly
			(pts
				(xy -2.100072 -0.750062) (xy -3.240024 -1.130046) (xy -3.240024 -0.370078)
			)
			(stroke
				(width 0)
				(type default)
			)
			(fill yes)
			(layer "F.Fab")
		)
		(fp_text user "16"
			(at -2.033016 -2.04343 0)
			(unlocked yes)
			(layer "F.SilkS")
			(effects
				(font
					(size 0.635 0.4064)
					(thickness 0.1524)
				)
				(justify left)
			)
		)
		(fp_text user "5"
			(at -1.452118 2.25171 0)
			(unlocked yes)
			(layer "F.SilkS")
			(effects
				(font
					(size 0.635 0.4064)
					(thickness 0.1524)
				)
				(justify left)
			)
		)
		(fp_text user "9"
			(at 1.508252 2.123186 0)
			(unlocked yes)
			(layer "F.SilkS")
			(effects
				(font
					(size 0.635 0.4064)
					(thickness 0.1524)
				)
				(justify left)
			)
		)
		(fp_text user "12"
			(at 1.616456 -1.820418 0)
			(unlocked yes)
			(layer "F.SilkS")
			(effects
				(font
					(size 0.635 0.4064)
					(thickness 0.1524)
				)
				(justify left)
			)
		)
		(fp_text user "16"
			(at -2.457958 -2.225675 0)
			(unlocked yes)
			(layer "F.Fab")
			(effects
				(font
					(size 0.78994 0.579882)
					(thickness 0.000001)
				)
				(justify left)
			)
		)
		(fp_text user "5"
			(at -1.737868 2.295525 0)
			(unlocked yes)
			(layer "F.Fab")
			(effects
				(font
					(size 0.78994 0.579882)
					(thickness 0.000001)
				)
				(justify left)
			)
		)
		(fp_text user "12"
			(at 1.708912 -1.514475 0)
			(unlocked yes)
			(layer "F.Fab")
			(effects
				(font
					(size 0.78994 0.579882)
					(thickness 0.000001)
				)
				(justify left)
			)
		)
		(fp_text user "9"
			(at 1.767586 1.584325 0)
			(unlocked yes)
			(layer "F.Fab")
			(effects
				(font
					(size 0.78994 0.579882)
					(thickness 0.000001)
				)
				(justify left)
			)
		)
		(pad "1" smd rect
			(at -1.474978 -0.750062 90)
			(size 0.254 0.8382)
			(layers "F.Cu" "F.Mask" "F.Paste")
			(net "P3V3_STB_NODE1_FB")
		)
		(pad "2" smd rect
			(at -1.474978 -0.249936 90)
			(size 0.254 0.8382)
			(layers "F.Cu" "F.Mask" "F.Paste")
			(net "P3V3_STB_NODE1_VREG5")
		)
		(pad "3" smd rect
			(at -1.474978 0.249936 90)
			(size 0.254 0.8382)
			(layers "F.Cu" "F.Mask" "F.Paste")
			(net "P3V3_STB_NODE1_SS")
		)
		(pad "4" smd rect
			(at -1.474978 0.750062 90)
			(size 0.254 0.8382)
			(layers "F.Cu" "F.Mask" "F.Paste")
			(net "GND")
		)
		(pad "5" smd rect
			(at -0.750062 1.474978)
			(size 0.254 0.8382)
			(layers "F.Cu" "F.Mask" "F.Paste")
			(net "PWRGD_NODE1_P3V3_STB_PG")
		)
		(pad "6" smd rect
			(at -0.249936 1.474978)
			(size 0.254 0.8382)
			(layers "F.Cu" "F.Mask" "F.Paste")
			(net "P3V3_STB_NODE1_EN")
		)
		(pad "7" smd rect
			(at 0.249936 1.474978)
			(size 0.254 0.8382)
			(layers "F.Cu" "F.Mask" "F.Paste")
			(net "GND")
		)
		(pad "8" smd rect
			(at 0.750062 1.474978)
			(size 0.254 0.8382)
			(layers "F.Cu" "F.Mask" "F.Paste")
			(net "GND")
		)
		(pad "9" smd rect
			(at 1.474978 0.750062 90)
			(size 0.254 0.8382)
			(layers "F.Cu" "F.Mask" "F.Paste")
			(net "SW_P3V3_STB_NODE1_PH")
		)
		(pad "10" smd rect
			(at 1.474978 0.249936 90)
			(size 0.254 0.8382)
			(layers "F.Cu" "F.Mask" "F.Paste")
			(net "SW_P3V3_STB_NODE1_PH")
		)
		(pad "11" smd rect
			(at 1.474978 -0.249936 90)
			(size 0.254 0.8382)
			(layers "F.Cu" "F.Mask" "F.Paste")
			(net "SW_P3V3_STB_NODE1_PH")
		)
		(pad "12" smd rect
			(at 1.474978 -0.750062 90)
			(size 0.254 0.8382)
			(layers "F.Cu" "F.Mask" "F.Paste")
			(net "SW_P3V3_STB_NODE1_BT")
		)
		(pad "13" smd rect
			(at 0.750062 -1.474978)
			(size 0.254 0.8382)
			(layers "F.Cu" "F.Mask" "F.Paste")
			(net "P12V_AUX")
		)
		(pad "14" smd rect
			(at 0.249936 -1.474978)
			(size 0.254 0.8382)
			(layers "F.Cu" "F.Mask" "F.Paste")
			(net "P12V_AUX")
		)
		(pad "15" smd rect
			(at -0.249936 -1.474978)
			(size 0.254 0.8382)
			(layers "F.Cu" "F.Mask" "F.Paste")
			(net "P5V_STB_NODE1")
		)
		(pad "16" smd rect
			(at -0.750062 -1.474978)
			(size 0.254 0.8382)
			(layers "F.Cu" "F.Mask" "F.Paste")
			(net "P3V3_STB_NODE1")
		)
		(pad "TH" smd rect
			(at 0 0 90)
			(size 1.7018 1.7018)
			(layers "F.Cu" "F.Mask" "F.Paste")
			(net "GND")
		)
		(zone
			(layer "F.Cu")
			(hatch none 0.5)
			(connect_pads
				(clearance 0)
			)
			(min_thickness 0.25)
			(keepout
				(tracks allowed)
				(vias not_allowed)
				(pads allowed)
				(copperpour not_allowed)
				(footprints allowed)
			)
			(placement
				(enabled no)
				(sheetname "")
			)
			(fill
				(thermal_gap 0.5)
				(thermal_bridge_width 0.5)
				(island_removal_mode 0)
			)
			(polygon
				(pts
					(xy 44.868084 -110.968536) (xy 46.849284 -110.968536) (xy 46.849284 -108.987336) (xy 44.868084 -108.987336)
					(xy 44.868084 -109.063536) (xy 46.773084 -109.063536) (xy 46.773084 -110.892336) (xy 44.944284 -110.892336)
					(xy 44.944284 -109.088936) (xy 44.868084 -109.088936)
				)
			)
		)
	)
	(footprint ""
		(layer "F.Cu")
		(at 170.765724 -133.640322 -90)
		(property "Reference" "R116"
			(at -7.610094 0.189992 90)
			(unlocked yes)
			(layer "F.SilkS")
			(effects
				(font
					(size 0.7874 0.5842)
					(thickness 0.1524)
				)
				(justify left)
			)
		)
		(property "Value" ""
			(at 0 0 270)
			(layer "F.Fab")
			(effects
				(font
					(size 1.27 1.27)
				)
			)
		)
		(duplicate_pad_numbers_are_jumpers no)
		(fp_line
			(start -0.7874 0.4064)
			(end -0.7874 -0.4064)
			(stroke
				(width 0.1524)
				(type default)
			)
			(layer "F.SilkS")
		)
		(fp_line
			(start 0.7874 0.4064)
			(end -0.7874 0.4064)
			(stroke
				(width 0.1524)
				(type default)
			)
			(layer "F.SilkS")
		)
		(fp_line
			(start -0.7874 -0.4064)
			(end 0.7874 -0.4064)
			(stroke
				(width 0.1524)
				(type default)
			)
			(layer "F.SilkS")
		)
		(fp_line
			(start 0.7874 -0.4064)
			(end 0.7874 0.4064)
			(stroke
				(width 0.1524)
				(type default)
			)
			(layer "F.SilkS")
		)
		(fp_poly
			(pts
				(xy -0.508 0.2794) (xy -0.508 0.2286) (xy -0.635 0.2286) (xy -0.635 -0.254) (xy -0.5334 -0.254)
				(xy -0.5334 -0.2794) (xy 0.5334 -0.2794) (xy 0.5334 -0.254) (xy 0.635 -0.254) (xy 0.635 0.254) (xy 0.5334 0.254)
				(xy 0.5334 0.2794)
			)
			(stroke
				(width 0)
				(type default)
			)
			(fill no)
			(layer "F.CrtYd")
		)
		(pad "1" smd rect
			(at 0.40005 0 270)
			(size 0.4572 0.508)
			(layers "F.Cu" "F.Mask" "F.Paste")
			(net "H_CPU_NODE1_THRMTRIP_L")
		)
		(pad "2" smd rect
			(at -0.40005 0 270)
			(size 0.4572 0.508)
			(layers "F.Cu" "F.Mask" "F.Paste")
			(net "P1V05_NODE1")
		)
	)
	(footprint ""
		(layer "F.Cu")
		(at 105.947718 -152.719278)
		(property "Reference" "PC42"
			(at -2.05486 4.649216 0)
			(unlocked yes)
			(layer "F.SilkS")
			(effects
				(font
					(size 0.635 0.4064)
					(thickness 0.1524)
				)
				(justify left)
			)
		)
		(property "Value" ""
			(at 0 0 0)
			(layer "F.Fab")
			(effects
				(font
					(size 1.27 1.27)
				)
			)
		)
		(duplicate_pad_numbers_are_jumpers no)
		(fp_line
			(start -0.7874 -0.4064)
			(end 0.7874 -0.4064)
			(stroke
				(width 0.1524)
				(type default)
			)
			(layer "F.SilkS")
		)
		(fp_line
			(start -0.7874 0.4064)
			(end -0.7874 -0.4064)
			(stroke
				(width 0.1524)
				(type default)
			)
			(layer "F.SilkS")
		)
		(fp_line
			(start 0 0.381)
			(end 0 -0.381)
			(stroke
				(width 0.1524)
				(type default)
			)
			(layer "F.SilkS")
		)
		(fp_line
			(start 0.7874 -0.4064)
			(end 0.7874 0.4064)
			(stroke
				(width 0.1524)
				(type default)
			)
			(layer "F.SilkS")
		)
		(fp_line
			(start 0.7874 0.4064)
			(end -0.7874 0.4064)
			(stroke
				(width 0.1524)
				(type default)
			)
			(layer "F.SilkS")
		)
		(fp_poly
			(pts
				(xy -0.5334 0.254) (xy -0.635 0.254) (xy -0.635 0.2286) (xy -0.635 -0.254) (xy -0.5334 -0.254) (xy -0.5334 -0.2794)
				(xy 0.5334 -0.2794) (xy 0.5334 -0.254) (xy 0.635 -0.254) (xy 0.635 0.254) (xy 0.5334 0.254) (xy 0.5334 0.2794)
				(xy -0.508 0.2794) (xy -0.5334 0.2794)
			)
			(stroke
				(width 0)
				(type default)
			)
			(fill no)
			(layer "F.CrtYd")
		)
		(pad "1" smd rect
			(at 0.40005 0)
			(size 0.4572 0.508)
			(layers "F.Cu" "F.Mask" "F.Paste")
			(net "P1V8_STB_NODE1_FB")
		)
		(pad "2" smd rect
			(at -0.40005 0)
			(size 0.4572 0.508)
			(layers "F.Cu" "F.Mask" "F.Paste")
			(net "P1V8_STB_NODE1")
		)
	)
	(footprint ""
		(layer "F.Cu")
		(at 62.291214 -148.121624 180)
		(property "Reference" "C264"
			(at 30.37078 7.27329 0)
			(unlocked yes)
			(layer "F.SilkS")
			(effects
				(font
					(size 0.7874 0.5842)
					(thickness 0.1524)
				)
				(justify left)
			)
		)
		(property "Value" ""
			(at 0 0 180)
			(layer "F.Fab")
			(effects
				(font
					(size 1.27 1.27)
				)
			)
		)
		(duplicate_pad_numbers_are_jumpers no)
		(fp_line
			(start 0.7874 0.4064)
			(end -0.7874 0.4064)
			(stroke
				(width 0.1524)
				(type default)
			)
			(layer "F.SilkS")
		)
		(fp_line
			(start 0.7874 -0.4064)
			(end 0.7874 0.4064)
			(stroke
				(width 0.1524)
				(type default)
			)
			(layer "F.SilkS")
		)
		(fp_line
			(start 0 0.381)
			(end 0 -0.381)
			(stroke
				(width 0.1524)
				(type default)
			)
			(layer "F.SilkS")
		)
		(fp_line
			(start -0.7874 0.4064)
			(end -0.7874 -0.4064)
			(stroke
				(width 0.1524)
				(type default)
			)
			(layer "F.SilkS")
		)
		(fp_line
			(start -0.7874 -0.4064)
			(end 0.7874 -0.4064)
			(stroke
				(width 0.1524)
				(type default)
			)
			(layer "F.SilkS")
		)
		(fp_poly
			(pts
				(xy -0.5334 0.254) (xy -0.635 0.254) (xy -0.635 0.2286) (xy -0.635 -0.254) (xy -0.5334 -0.254) (xy -0.5334 -0.2794)
				(xy 0.5334 -0.2794) (xy 0.5334 -0.254) (xy 0.635 -0.254) (xy 0.635 0.254) (xy 0.5334 0.254) (xy 0.5334 0.2794)
				(xy -0.508 0.2794) (xy -0.5334 0.2794)
			)
			(stroke
				(width 0)
				(type default)
			)
			(fill no)
			(layer "F.CrtYd")
		)
		(pad "1" smd rect
			(at 0.40005 0 180)
			(size 0.4572 0.508)
			(layers "F.Cu" "F.Mask" "F.Paste")
			(net "BMC_NODE1_DACAV33")
		)
		(pad "2" smd rect
			(at -0.40005 0 180)
			(size 0.4572 0.508)
			(layers "F.Cu" "F.Mask" "F.Paste")
			(net "GND")
		)
	)
)
